FILE_TYPE = CONNECTIVITY;
{Allegro Design Entry HDL 16.6-p007 (v16-6-112F) 10/10/2012}
"PAGE_NUMBER" = 244;
0"NC";
1"P3E_CPU0_PE1_PCH_TXN<15:8>";
2"P3E_CPU0_PE1_PCH_CON_TXP<15:8>";
3"P3E_CPU0_PE1_PCH_TXP<15:8>";
4"P3E_CPU0_PE1_PCH_CON_TXN<15:8>";
5"P3E_CPU0_PE1_PCH_CON_RXP<15:8>";
6"P3E_CPU0_PE1_PCH_RXP<15:8>";
7"P3E_CPU0_PE1_PCH_CON_RXN<15:8>";
8"P3E_CPU0_PE1_PCH_RXN<15:8>";
9"P3E_CPU0_PE1_PCH_RXP<15>";
10"P3E_CPU0_PE1_PCH_RXP<14>";
11"P3E_CPU0_PE1_PCH_RXP<13>";
12"P3E_CPU0_PE1_PCH_CON_RXN<8>";
13"P3E_CPU0_PE1_PCH_CON_RXP<14>";
14"P3E_CPU0_PE1_PCH_CON_RXP<12>";
15"P3E_CPU0_PE1_PCH_CON_RXP<10>";
16"P3E_CPU0_PE1_PCH_CON_TXP<11>";
17"P3E_CPU0_PE1_PCH_TXN<15>";
18"P3E_CPU0_PE1_PCH_CON_TXN<14>";
19"P3E_CPU0_PE1_PCH_TXP<13>";
20"P3E_CPU0_PE1_PCH_CON_TXP<10>";
21"P3E_CPU0_PE1_PCH_TXP<11>";
22"P3E_CPU0_PE1_PCH_TXP<12>";
23"P3E_CPU0_PE1_PCH_RXN<15>";
24"P3E_CPU0_PE1_PCH_RXP<8>";
25"P3E_CPU0_PE1_PCH_RXN<8>";
26"P3E_CPU0_PE1_PCH_RXN<10>";
27"P3E_CPU0_PE1_PCH_RXN<9>";
28"P3E_CPU0_PE1_PCH_RXN<12>";
29"P3E_CPU0_PE1_PCH_RXN<11>";
30"P3E_CPU0_PE1_PCH_CON_RXN<9>";
31"P3E_CPU0_PE1_PCH_CON_RXN<10>";
32"P3E_CPU0_PE1_PCH_CON_RXN<11>";
33"P3E_CPU0_PE1_PCH_CON_RXN<12>";
34"P3E_CPU0_PE1_PCH_RXP<10>";
35"P3E_CPU0_PE1_PCH_RXP<12>";
36"P3E_CPU0_PE1_PCH_CON_RXP<8>";
37"P3E_CPU0_PE1_PCH_RXP<9>";
38"P3E_CPU0_PE1_PCH_RXP<11>";
39"P3E_CPU0_PE1_PCH_CON_RXP<9>";
40"P3E_CPU0_PE1_PCH_CON_RXP<11>";
41"P3E_CPU0_PE1_PCH_CON_RXP<13>";
42"P3E_CPU0_PE1_PCH_RXN<14>";
43"P3E_CPU0_PE1_PCH_RXN<13>";
44"P3E_CPU0_PE1_PCH_CON_RXN<14>";
45"P3E_CPU0_PE1_PCH_CON_RXN<13>";
46"P3E_CPU0_PE1_PCH_CON_RXN<15>";
47"P3E_CPU0_PE1_PCH_TXN<10>";
48"P3E_CPU0_PE1_PCH_TXN<8>";
49"P3E_CPU0_PE1_PCH_TXN<9>";
50"P3E_CPU0_PE1_PCH_CON_TXN<8>";
51"P3E_CPU0_PE1_PCH_CON_TXN<10>";
52"P3E_CPU0_PE1_PCH_CON_TXN<9>";
53"P3E_CPU0_PE1_PCH_TXP<8>";
54"P3E_CPU0_PE1_PCH_TXP<10>";
55"P3E_CPU0_PE1_PCH_TXP<9>";
56"P3E_CPU0_PE1_PCH_CON_TXP<8>";
57"P3E_CPU0_PE1_PCH_CON_RXP<15>";
58"P3E_CPU0_PE1_PCH_CON_TXP<9>";
59"P3E_CPU0_PE1_PCH_TXN<12>";
60"P3E_CPU0_PE1_PCH_TXN<11>";
61"P3E_CPU0_PE1_PCH_TXN<13>";
62"P3E_CPU0_PE1_PCH_TXN<14>";
63"P3E_CPU0_PE1_PCH_CON_TXN<11>";
64"P3E_CPU0_PE1_PCH_CON_TXN<13>";
65"P3E_CPU0_PE1_PCH_CON_TXN<12>";
66"P3E_CPU0_PE1_PCH_CON_TXN<15>";
67"P3E_CPU0_PE1_PCH_TXP<14>";
68"P3E_CPU0_PE1_PCH_TXP<15>";
69"P3E_CPU0_PE1_PCH_CON_TXP<12>";
70"P3E_CPU0_PE1_PCH_CON_TXP<14>";
71"P3E_CPU0_PE1_PCH_CON_TXP<13>";
72"P3E_CPU0_PE1_PCH_CON_TXP<15>";
%"TAP"
"7","(-5925,1475)","0","mstr_standard","I1";
;
CDS_LIB"mstr_standard"
BODY_TYPE"PLUMBING"
HDL_TAP"TRUE";
"B \NAC \NWC"2;
"S \NAC"
BN"15"72;
%"TAP"
"3","(-2500,3575)","0","mstr_standard","I100";
;
CDS_LIB"mstr_standard"
BODY_TYPE"PLUMBING"
HDL_TAP"TRUE";
"B \NAC \NWC"8;
"S \NAC"
BN"10"26;
%"TAP"
"3","(-2300,3575)","0","mstr_standard","I101";
;
CDS_LIB"mstr_standard"
BODY_TYPE"PLUMBING"
HDL_TAP"TRUE";
"B \NAC \NWC"8;
"S \NAC"
BN"9"27;
%"TAP"
"3","(-2100,3575)","0","mstr_standard","I102";
;
CDS_LIB"mstr_standard"
BODY_TYPE"PLUMBING"
HDL_TAP"TRUE";
"B \NAC \NWC"8;
"S \NAC"
BN"8"25;
%"RES"
"2","(-2025,2025)","0","mstr_discrete","I103";
;
CDS_SEC"1"
$SEC"1"
CDS_LOCATION"R785"
CDS_LIB"mstr_discrete"
ROOM"PCIE_STEERING"
$LOCATION"R785"
PACK_TYPE"0402"
TOLERANCE"5%"
VALUE"0.0"
WATTAGE"1/16W"
MATERIAL"CHIP"
PART_NUMBER"G21497-005";
"A"
$PN"1"24;
"B"
$PN"2"36;
%"TAP"
"3","(-5925,2275)","0","mstr_standard","I11";
;
CDS_LIB"mstr_standard"
BODY_TYPE"PLUMBING"
HDL_TAP"TRUE";
"B \NAC \NWC"3;
"S \NAC"
BN"15"68;
%"CAP"
"1","(-5725,2025)","2","mstr_discrete","I12";
;
CDS_SEC"1"
$SEC"1"
CDS_LOCATION"C827"
CDS_LIB"mstr_discrete"
ROOM"OCP_STEERING"
PART_NUMBER"A36096-155"
$LOCATION"C827"
MATERIAL"X7R"
PACK_TYPE"0402"
VALUE"0.22UF"
VOLTAGE"16V"
TOLERANCE"10%";
"A"
$PN"1"67;
"B"
$PN"2"70;
%"TAP"
"3","(-5725,2275)","0","mstr_standard","I13";
;
CDS_LIB"mstr_standard"
BODY_TYPE"PLUMBING"
HDL_TAP"TRUE";
"B \NAC \NWC"3;
"S \NAC"
BN"14"67;
%"TAP"
"7","(-6025,2775)","0","mstr_standard","I14";
;
CDS_LIB"mstr_standard"
BODY_TYPE"PLUMBING"
HDL_TAP"TRUE";
"B \NAC \NWC"4;
"S \NAC"
BN"15"66;
%"TAP"
"7","(-5825,2775)","0","mstr_standard","I15";
;
CDS_LIB"mstr_standard"
BODY_TYPE"PLUMBING"
HDL_TAP"TRUE";
"B \NAC \NWC"4;
"S \NAC"
BN"14"18;
%"TAP"
"3","(-5525,2275)","0","mstr_standard","I16";
;
CDS_LIB"mstr_standard"
BODY_TYPE"PLUMBING"
HDL_TAP"TRUE";
"B \NAC \NWC"3;
"S \NAC"
BN"13"19;
%"CAP"
"1","(-5325,2025)","2","mstr_discrete","I17";
;
CDS_SEC"1"
$SEC"1"
CDS_LOCATION"C841"
CDS_LIB"mstr_discrete"
ROOM"OCP_STEERING"
MATERIAL"X7R"
VOLTAGE"16V"
VALUE"0.22UF"
$LOCATION"C841"
TOLERANCE"10%"
PART_NUMBER"A36096-155"
PACK_TYPE"0402";
"A"
$PN"1"22;
"B"
$PN"2"69;
%"TAP"
"3","(-5325,2275)","0","mstr_standard","I18";
;
CDS_LIB"mstr_standard"
BODY_TYPE"PLUMBING"
HDL_TAP"TRUE";
"B \NAC \NWC"3;
"S \NAC"
BN"12"22;
%"TAP"
"3","(-5125,2275)","0","mstr_standard","I19";
;
CDS_LIB"mstr_standard"
BODY_TYPE"PLUMBING"
HDL_TAP"TRUE";
"B \NAC \NWC"3;
"S \NAC"
BN"11"21;
%"CAP"
"1","(-5925,1725)","2","mstr_discrete","I2";
;
CDS_SEC"1"
$SEC"1"
CDS_LOCATION"C831"
CDS_LIB"mstr_discrete"
ROOM"OCP_STEERING"
VALUE"0.22UF"
PACK_TYPE"0402"
MATERIAL"X7R"
TOLERANCE"10%"
PART_NUMBER"A36096-155"
$LOCATION"C831"
VOLTAGE"16V";
"A"
$PN"1"68;
"B"
$PN"2"72;
%"TAP"
"7","(-5625,2775)","0","mstr_standard","I20";
;
CDS_LIB"mstr_standard"
BODY_TYPE"PLUMBING"
HDL_TAP"TRUE";
"B \NAC \NWC"4;
"S \NAC"
BN"13"64;
%"TAP"
"7","(-5425,2775)","0","mstr_standard","I21";
;
CDS_LIB"mstr_standard"
BODY_TYPE"PLUMBING"
HDL_TAP"TRUE";
"B \NAC \NWC"4;
"S \NAC"
BN"12"65;
%"TAP"
"7","(-5225,2775)","0","mstr_standard","I22";
;
CDS_LIB"mstr_standard"
BODY_TYPE"PLUMBING"
HDL_TAP"TRUE";
"B \NAC \NWC"4;
"S \NAC"
BN"11"63;
%"CAP"
"1","(-6025,3025)","2","mstr_discrete","I23";
;
CDS_SEC"1"
$SEC"1"
CDS_LOCATION"C830"
ROOM"OCP_STEERING"
CDS_LIB"mstr_discrete"
$LOCATION"C830"
VALUE"0.22UF"
MATERIAL"X7R"
VOLTAGE"16V"
PACK_TYPE"0402"
PART_NUMBER"A36096-155"
TOLERANCE"10%";
"A"
$PN"1"17;
"B"
$PN"2"66;
%"CAP"
"1","(-5825,3325)","2","mstr_discrete","I24";
;
CDS_SEC"1"
$SEC"1"
CDS_LOCATION"C826"
ROOM"OCP_STEERING"
CDS_LIB"mstr_discrete"
VALUE"0.22UF"
$LOCATION"C826"
TOLERANCE"10%"
PACK_TYPE"0402"
MATERIAL"X7R"
VOLTAGE"16V"
PART_NUMBER"A36096-155";
"A"
$PN"1"62;
"B"
$PN"2"18;
%"TAP"
"3","(-6025,3575)","0","mstr_standard","I25";
;
CDS_LIB"mstr_standard"
BODY_TYPE"PLUMBING"
HDL_TAP"TRUE";
"B \NAC \NWC"1;
"S \NAC"
BN"15"17;
%"TAP"
"3","(-5825,3575)","0","mstr_standard","I26";
;
CDS_LIB"mstr_standard"
BODY_TYPE"PLUMBING"
HDL_TAP"TRUE";
"B \NAC \NWC"1;
"S \NAC"
BN"14"62;
%"TAP"
"3","(-5625,3575)","0","mstr_standard","I27";
;
CDS_LIB"mstr_standard"
BODY_TYPE"PLUMBING"
HDL_TAP"TRUE";
"B \NAC \NWC"1;
"S \NAC"
BN"13"61;
%"CAP"
"1","(-5625,3025)","2","mstr_discrete","I28";
;
CDS_SEC"1"
$SEC"1"
CDS_LOCATION"C828"
CDS_LIB"mstr_discrete"
ROOM"OCP_STEERING"
TOLERANCE"10%"
MATERIAL"X7R"
PACK_TYPE"0402"
PART_NUMBER"A36096-155"
VALUE"0.22UF"
$LOCATION"C828"
VOLTAGE"16V";
"A"
$PN"1"61;
"B"
$PN"2"64;
%"CAP"
"1","(-5425,3325)","2","mstr_discrete","I29";
;
CDS_SEC"1"
$SEC"1"
CDS_LOCATION"C840"
CDS_LIB"mstr_discrete"
ROOM"OCP_STEERING"
$LOCATION"C840"
VOLTAGE"16V"
TOLERANCE"10%"
MATERIAL"X7R"
PACK_TYPE"0402"
PART_NUMBER"A36096-155"
VALUE"0.22UF";
"A"
$PN"1"59;
"B"
$PN"2"65;
%"TAP"
"7","(-5725,1475)","0","mstr_standard","I3";
;
CDS_LIB"mstr_standard"
BODY_TYPE"PLUMBING"
HDL_TAP"TRUE";
"B \NAC \NWC"2;
"S \NAC"
BN"14"70;
%"CAP"
"1","(-5225,3025)","2","mstr_discrete","I30";
;
CDS_SEC"1"
$SEC"1"
CDS_LOCATION"C832"
CDS_LIB"mstr_discrete"
ROOM"OCP_STEERING"
MATERIAL"X7R"
$LOCATION"C832"
TOLERANCE"10%"
VOLTAGE"16V"
PACK_TYPE"0402"
VALUE"0.22UF"
PART_NUMBER"A36096-155";
"A"
$PN"1"60;
"B"
$PN"2"63;
%"TAP"
"3","(-5425,3575)","0","mstr_standard","I31";
;
CDS_LIB"mstr_standard"
BODY_TYPE"PLUMBING"
HDL_TAP"TRUE";
"B \NAC \NWC"1;
"S \NAC"
BN"12"59;
%"TAP"
"3","(-5225,3575)","0","mstr_standard","I32";
;
CDS_LIB"mstr_standard"
BODY_TYPE"PLUMBING"
HDL_TAP"TRUE";
"B \NAC \NWC"1;
"S \NAC"
BN"11"60;
%"TAP"
"7","(-4925,1475)","0","mstr_standard","I33";
;
CDS_LIB"mstr_standard"
BODY_TYPE"PLUMBING"
HDL_TAP"TRUE";
"B \NAC \NWC"2;
"S \NAC"
BN"10"20;
%"TAP"
"7","(-4725,1475)","0","mstr_standard","I34";
;
CDS_LIB"mstr_standard"
BODY_TYPE"PLUMBING"
HDL_TAP"TRUE";
"B \NAC \NWC"2;
"S \NAC"
BN"9"58;
%"CAP"
"1","(-4725,1725)","2","mstr_discrete","I35";
;
CDS_SEC"1"
$SEC"1"
CDS_LOCATION"C845"
CDS_LIB"mstr_discrete"
ROOM"OCP_STEERING"
PACK_TYPE"0402"
PART_NUMBER"A36096-155"
MATERIAL"X7R"
VALUE"0.22UF"
$LOCATION"C845"
VOLTAGE"16V"
TOLERANCE"10%";
"A"
$PN"1"55;
"B"
$PN"2"58;
%"TAP"
"7","(-4525,1475)","0","mstr_standard","I36";
;
CDS_LIB"mstr_standard"
BODY_TYPE"PLUMBING"
HDL_TAP"TRUE";
"B \NAC \NWC"2;
"S \NAC"
BN"8"56;
%"TAP"
"7","(-3425,1475)","0","mstr_standard","I38";
;
CDS_LIB"mstr_standard"
BODY_TYPE"PLUMBING"
HDL_TAP"TRUE";
"B \NAC \NWC"5;
"S \NAC"
BN"15"57;
%"RES"
"2","(-3425,1725)","0","mstr_discrete","I39";
;
CDS_SEC"1"
$SEC"1"
CDS_LOCATION"R767"
CDS_LIB"mstr_discrete"
ROOM"PCIE_STEERING"
VALUE"0.0"
MATERIAL"CHIP"
TOLERANCE"5%"
PART_NUMBER"G21497-005"
PACK_TYPE"0402"
WATTAGE"1/16W"
$LOCATION"R767";
"A"
$PN"1"9;
"B"
$PN"2"57;
%"TAP"
"7","(-5525,1475)","0","mstr_standard","I4";
;
CDS_LIB"mstr_standard"
BODY_TYPE"PLUMBING"
HDL_TAP"TRUE";
"B \NAC \NWC"2;
"S \NAC"
BN"13"71;
%"TAP"
"7","(-3225,1475)","0","mstr_standard","I40";
;
CDS_LIB"mstr_standard"
BODY_TYPE"PLUMBING"
HDL_TAP"TRUE";
"B \NAC \NWC"5;
"S \NAC"
BN"14"13;
%"CAP"
"1","(-4925,2025)","2","mstr_discrete","I41";
;
CDS_SEC"1"
$SEC"1"
CDS_LOCATION"C835"
CDS_LIB"mstr_discrete"
ROOM"OCP_STEERING"
PACK_TYPE"0402"
VOLTAGE"16V"
TOLERANCE"10%"
$LOCATION"C835"
VALUE"0.22UF"
MATERIAL"X7R"
PART_NUMBER"A36096-155";
"A"
$PN"1"54;
"B"
$PN"2"20;
%"TAP"
"3","(-4925,2275)","0","mstr_standard","I42";
;
CDS_LIB"mstr_standard"
BODY_TYPE"PLUMBING"
HDL_TAP"TRUE";
"B \NAC \NWC"3;
"S \NAC"
BN"10"54;
%"TAP"
"3","(-4725,2275)","0","mstr_standard","I43";
;
CDS_LIB"mstr_standard"
BODY_TYPE"PLUMBING"
HDL_TAP"TRUE";
"B \NAC \NWC"3;
"S \NAC"
BN"9"55;
%"TAP"
"7","(-5025,2775)","0","mstr_standard","I44";
;
CDS_LIB"mstr_standard"
BODY_TYPE"PLUMBING"
HDL_TAP"TRUE";
"B \NAC \NWC"4;
"S \NAC"
BN"10"51;
%"TAP"
"7","(-4825,2775)","0","mstr_standard","I45";
;
CDS_LIB"mstr_standard"
BODY_TYPE"PLUMBING"
HDL_TAP"TRUE";
"B \NAC \NWC"4;
"S \NAC"
BN"9"52;
%"TAP"
"7","(-4625,2775)","0","mstr_standard","I46";
;
CDS_LIB"mstr_standard"
BODY_TYPE"PLUMBING"
HDL_TAP"TRUE";
"B \NAC \NWC"4;
"S \NAC"
BN"8"50;
%"CAP"
"1","(-4525,2025)","2","mstr_discrete","I47";
;
CDS_SEC"1"
$SEC"1"
CDS_LOCATION"C843"
CDS_LIB"mstr_discrete"
ROOM"OCP_STEERING"
$LOCATION"C843"
VALUE"0.22UF"
VOLTAGE"16V"
PACK_TYPE"0402"
MATERIAL"X7R"
TOLERANCE"10%"
PART_NUMBER"A36096-155";
"A"
$PN"1"53;
"B"
$PN"2"56;
%"TAP"
"3","(-4525,2275)","0","mstr_standard","I48";
;
CDS_LIB"mstr_standard"
BODY_TYPE"PLUMBING"
HDL_TAP"TRUE";
"B \NAC \NWC"3;
"S \NAC"
BN"8"53;
%"CAP"
"1","(-5525,1725)","2","mstr_discrete","I5";
;
CDS_SEC"1"
$SEC"1"
CDS_LOCATION"C829"
CDS_LIB"mstr_discrete"
ROOM"OCP_STEERING"
$LOCATION"C829"
TOLERANCE"10%"
VOLTAGE"16V"
VALUE"0.22UF"
PACK_TYPE"0402"
PART_NUMBER"A36096-155"
MATERIAL"X7R";
"A"
$PN"1"19;
"B"
$PN"2"71;
%"CAP"
"1","(-5025,3325)","2","mstr_discrete","I50";
;
CDS_SEC"1"
$SEC"1"
CDS_LOCATION"C834"
ROOM"OCP_STEERING"
CDS_LIB"mstr_discrete"
$LOCATION"C834"
PART_NUMBER"A36096-155"
VALUE"0.22UF"
MATERIAL"X7R"
PACK_TYPE"0402"
VOLTAGE"16V"
TOLERANCE"10%";
"A"
$PN"1"47;
"B"
$PN"2"51;
%"CAP"
"1","(-4825,3025)","2","mstr_discrete","I51";
;
CDS_SEC"1"
$SEC"1"
CDS_LOCATION"C844"
ROOM"OCP_STEERING"
CDS_LIB"mstr_discrete"
PACK_TYPE"0402"
$LOCATION"C844"
VALUE"0.22UF"
VOLTAGE"16V"
MATERIAL"X7R"
TOLERANCE"10%"
PART_NUMBER"A36096-155";
"A"
$PN"1"49;
"B"
$PN"2"52;
%"CAP"
"1","(-4625,3300)","2","mstr_discrete","I52";
;
CDS_SEC"1"
$SEC"1"
CDS_LOCATION"C842"
ROOM"OCP_STEERING"
CDS_LIB"mstr_discrete"
PART_NUMBER"A36096-155"
PACK_TYPE"0402"
VALUE"0.22UF"
VOLTAGE"16V"
$LOCATION"C842"
TOLERANCE"10%"
MATERIAL"X7R";
"A"
$PN"1"48;
"B"
$PN"2"50;
%"TAP"
"3","(-5025,3575)","0","mstr_standard","I53";
;
CDS_LIB"mstr_standard"
BODY_TYPE"PLUMBING"
HDL_TAP"TRUE";
"B \NAC \NWC"1;
"S \NAC"
BN"10"47;
%"TAP"
"3","(-4825,3575)","0","mstr_standard","I54";
;
CDS_LIB"mstr_standard"
BODY_TYPE"PLUMBING"
HDL_TAP"TRUE";
"B \NAC \NWC"1;
"S \NAC"
BN"9"49;
%"TAP"
"3","(-4625,3575)","0","mstr_standard","I55";
;
CDS_LIB"mstr_standard"
BODY_TYPE"PLUMBING"
HDL_TAP"TRUE";
"B \NAC \NWC"1;
"S \NAC"
BN"8"48;
%"TAP"
"3","(-3425,2275)","0","mstr_standard","I57";
;
CDS_LIB"mstr_standard"
BODY_TYPE"PLUMBING"
HDL_TAP"TRUE";
"B \NAC \NWC"6;
"S \NAC"
BN"15"9;
%"RES"
"2","(-3225,2025)","0","mstr_discrete","I58";
;
CDS_SEC"1"
$SEC"1"
CDS_LOCATION"R769"
CDS_LIB"mstr_discrete"
ROOM"PCIE_STEERING"
VALUE"0.0"
TOLERANCE"5%"
WATTAGE"1/16W"
MATERIAL"CHIP"
PART_NUMBER"G21497-005"
PACK_TYPE"0402"
$LOCATION"R769";
"A"
$PN"1"10;
"B"
$PN"2"13;
%"TAP"
"3","(-3225,2275)","0","mstr_standard","I59";
;
CDS_LIB"mstr_standard"
BODY_TYPE"PLUMBING"
HDL_TAP"TRUE";
"B \NAC \NWC"6;
"S \NAC"
BN"14"10;
%"TAP"
"7","(-5325,1475)","0","mstr_standard","I6";
;
CDS_LIB"mstr_standard"
BODY_TYPE"PLUMBING"
HDL_TAP"TRUE";
"B \NAC \NWC"2;
"S \NAC"
BN"12"69;
%"TAP"
"7","(-3500,2775)","0","mstr_standard","I60";
;
CDS_LIB"mstr_standard"
BODY_TYPE"PLUMBING"
HDL_TAP"TRUE";
"B \NAC \NWC"7;
"S \NAC"
BN"15"46;
%"TAP"
"7","(-3300,2775)","0","mstr_standard","I61";
;
CDS_LIB"mstr_standard"
BODY_TYPE"PLUMBING"
HDL_TAP"TRUE";
"B \NAC \NWC"7;
"S \NAC"
BN"14"44;
%"TAP"
"7","(-3100,2775)","0","mstr_standard","I62";
;
CDS_LIB"mstr_standard"
BODY_TYPE"PLUMBING"
HDL_TAP"TRUE";
"B \NAC \NWC"7;
"S \NAC"
BN"13"45;
%"RES"
"2","(-3500,3025)","0","mstr_discrete","I64";
;
CDS_SEC"1"
$SEC"1"
CDS_LOCATION"R760"
CDS_LIB"mstr_discrete"
ROOM"PCIE_STEERING"
MATERIAL"CHIP"
$LOCATION"R760"
TOLERANCE"5%"
VALUE"0.0"
WATTAGE"1/16W"
PART_NUMBER"G21497-005"
PACK_TYPE"0402";
"A"
$PN"1"23;
"B"
$PN"2"46;
%"RES"
"2","(-3100,3025)","0","mstr_discrete","I65";
;
CDS_SEC"1"
$SEC"1"
CDS_LOCATION"R771"
CDS_LIB"mstr_discrete"
ROOM"PCIE_STEERING"
PART_NUMBER"G21497-005"
VALUE"0.0"
MATERIAL"CHIP"
WATTAGE"1/16W"
TOLERANCE"5%"
PACK_TYPE"0402"
$LOCATION"R771";
"A"
$PN"1"43;
"B"
$PN"2"45;
%"RES"
"2","(-3300,3325)","0","mstr_discrete","I66";
;
CDS_SEC"1"
$SEC"1"
CDS_LOCATION"R768"
CDS_LIB"mstr_discrete"
ROOM"PCIE_STEERING"
PACK_TYPE"0402"
MATERIAL"CHIP"
TOLERANCE"5%"
PART_NUMBER"G21497-005"
WATTAGE"1/16W"
VALUE"0.0"
$LOCATION"R768";
"A"
$PN"1"42;
"B"
$PN"2"44;
%"TAP"
"3","(-3500,3575)","0","mstr_standard","I67";
;
CDS_LIB"mstr_standard"
BODY_TYPE"PLUMBING"
HDL_TAP"TRUE";
"B \NAC \NWC"8;
"S \NAC"
BN"15"23;
%"TAP"
"3","(-3300,3575)","0","mstr_standard","I68";
;
CDS_LIB"mstr_standard"
BODY_TYPE"PLUMBING"
HDL_TAP"TRUE";
"B \NAC \NWC"8;
"S \NAC"
BN"14"42;
%"TAP"
"3","(-3100,3575)","0","mstr_standard","I69";
;
CDS_LIB"mstr_standard"
BODY_TYPE"PLUMBING"
HDL_TAP"TRUE";
"B \NAC \NWC"8;
"S \NAC"
BN"13"43;
%"TAP"
"7","(-5125,1475)","0","mstr_standard","I7";
;
CDS_LIB"mstr_standard"
BODY_TYPE"PLUMBING"
HDL_TAP"TRUE";
"B \NAC \NWC"2;
"S \NAC"
BN"11"16;
%"TAP"
"7","(-3025,1475)","0","mstr_standard","I70";
;
CDS_LIB"mstr_standard"
BODY_TYPE"PLUMBING"
HDL_TAP"TRUE";
"B \NAC \NWC"5;
"S \NAC"
BN"13"41;
%"TAP"
"7","(-2825,1475)","0","mstr_standard","I71";
;
CDS_LIB"mstr_standard"
BODY_TYPE"PLUMBING"
HDL_TAP"TRUE";
"B \NAC \NWC"5;
"S \NAC"
BN"12"14;
%"RES"
"2","(-3025,1725)","0","mstr_discrete","I72";
;
CDS_SEC"1"
$SEC"1"
CDS_LOCATION"R774"
CDS_LIB"mstr_discrete"
ROOM"PCIE_STEERING"
WATTAGE"1/16W"
TOLERANCE"5%"
VALUE"0.0"
MATERIAL"CHIP"
PART_NUMBER"G21497-005"
PACK_TYPE"0402"
$LOCATION"R774";
"A"
$PN"1"11;
"B"
$PN"2"41;
%"TAP"
"7","(-2625,1475)","0","mstr_standard","I73";
;
CDS_LIB"mstr_standard"
BODY_TYPE"PLUMBING"
HDL_TAP"TRUE";
"B \NAC \NWC"5;
"S \NAC"
BN"11"40;
%"RES"
"2","(-2625,1725)","0","mstr_discrete","I74";
;
CDS_SEC"1"
$SEC"1"
CDS_LOCATION"R779"
CDS_LIB"mstr_discrete"
ROOM"PCIE_STEERING"
$LOCATION"R779"
TOLERANCE"5%"
VALUE"0.0"
PACK_TYPE"0402"
PART_NUMBER"G21497-005"
MATERIAL"CHIP"
WATTAGE"1/16W";
"A"
$PN"1"38;
"B"
$PN"2"40;
%"TAP"
"7","(-2425,1475)","0","mstr_standard","I75";
;
CDS_LIB"mstr_standard"
BODY_TYPE"PLUMBING"
HDL_TAP"TRUE";
"B \NAC \NWC"5;
"S \NAC"
BN"10"15;
%"TAP"
"7","(-2225,1475)","0","mstr_standard","I76";
;
CDS_LIB"mstr_standard"
BODY_TYPE"PLUMBING"
HDL_TAP"TRUE";
"B \NAC \NWC"5;
"S \NAC"
BN"9"39;
%"RES"
"2","(-2225,1725)","0","mstr_discrete","I77";
;
CDS_SEC"1"
$SEC"1"
CDS_LOCATION"R783"
CDS_LIB"mstr_discrete"
ROOM"PCIE_STEERING"
PACK_TYPE"0402"
VALUE"0.0"
MATERIAL"CHIP"
PART_NUMBER"G21497-005"
WATTAGE"1/16W"
TOLERANCE"5%"
$LOCATION"R783";
"A"
$PN"1"37;
"B"
$PN"2"39;
%"TAP"
"7","(-2025,1475)","0","mstr_standard","I78";
;
CDS_LIB"mstr_standard"
BODY_TYPE"PLUMBING"
HDL_TAP"TRUE";
"B \NAC \NWC"5;
"S \NAC"
BN"8"36;
%"CAP"
"1","(-5125,1725)","2","mstr_discrete","I8";
;
CDS_SEC"1"
$SEC"1"
CDS_LOCATION"C833"
CDS_LIB"mstr_discrete"
ROOM"OCP_STEERING"
$LOCATION"C833"
VALUE"0.22UF"
VOLTAGE"16V"
MATERIAL"X7R"
PACK_TYPE"0402"
PART_NUMBER"A36096-155"
TOLERANCE"10%";
"A"
$PN"1"21;
"B"
$PN"2"16;
%"RES"
"2","(-2825,2025)","0","mstr_discrete","I80";
;
CDS_SEC"1"
$SEC"1"
CDS_LOCATION"R777"
CDS_LIB"mstr_discrete"
ROOM"PCIE_STEERING"
WATTAGE"1/16W"
TOLERANCE"5%"
VALUE"0.0"
PACK_TYPE"0402"
PART_NUMBER"G21497-005"
MATERIAL"CHIP"
$LOCATION"R777";
"A"
$PN"1"35;
"B"
$PN"2"14;
%"TAP"
"3","(-3025,2275)","0","mstr_standard","I81";
;
CDS_LIB"mstr_standard"
BODY_TYPE"PLUMBING"
HDL_TAP"TRUE";
"B \NAC \NWC"6;
"S \NAC"
BN"13"11;
%"TAP"
"3","(-2825,2275)","0","mstr_standard","I82";
;
CDS_LIB"mstr_standard"
BODY_TYPE"PLUMBING"
HDL_TAP"TRUE";
"B \NAC \NWC"6;
"S \NAC"
BN"12"35;
%"TAP"
"3","(-2625,2275)","0","mstr_standard","I83";
;
CDS_LIB"mstr_standard"
BODY_TYPE"PLUMBING"
HDL_TAP"TRUE";
"B \NAC \NWC"6;
"S \NAC"
BN"11"38;
%"TAP"
"7","(-2900,2775)","0","mstr_standard","I84";
;
CDS_LIB"mstr_standard"
BODY_TYPE"PLUMBING"
HDL_TAP"TRUE";
"B \NAC \NWC"7;
"S \NAC"
BN"12"33;
%"TAP"
"7","(-2700,2775)","0","mstr_standard","I85";
;
CDS_LIB"mstr_standard"
BODY_TYPE"PLUMBING"
HDL_TAP"TRUE";
"B \NAC \NWC"7;
"S \NAC"
BN"11"32;
%"RES"
"2","(-2425,2025)","0","mstr_discrete","I86";
;
CDS_SEC"1"
$SEC"1"
CDS_LOCATION"R781"
CDS_LIB"mstr_discrete"
ROOM"PCIE_STEERING"
MATERIAL"CHIP"
PART_NUMBER"G21497-005"
PACK_TYPE"0402"
WATTAGE"1/16W"
TOLERANCE"5%"
VALUE"0.0"
$LOCATION"R781";
"A"
$PN"1"34;
"B"
$PN"2"15;
%"TAP"
"3","(-2425,2275)","0","mstr_standard","I87";
;
CDS_LIB"mstr_standard"
BODY_TYPE"PLUMBING"
HDL_TAP"TRUE";
"B \NAC \NWC"6;
"S \NAC"
BN"10"34;
%"TAP"
"3","(-2225,2275)","0","mstr_standard","I88";
;
CDS_LIB"mstr_standard"
BODY_TYPE"PLUMBING"
HDL_TAP"TRUE";
"B \NAC \NWC"6;
"S \NAC"
BN"9"37;
%"TAP"
"3","(-2025,2275)","0","mstr_standard","I89";
;
CDS_LIB"mstr_standard"
BODY_TYPE"PLUMBING"
HDL_TAP"TRUE";
"B \NAC \NWC"6;
"S \NAC"
BN"8"24;
%"TAP"
"7","(-2500,2775)","0","mstr_standard","I90";
;
CDS_LIB"mstr_standard"
BODY_TYPE"PLUMBING"
HDL_TAP"TRUE";
"B \NAC \NWC"7;
"S \NAC"
BN"10"31;
%"TAP"
"7","(-2300,2775)","0","mstr_standard","I91";
;
CDS_LIB"mstr_standard"
BODY_TYPE"PLUMBING"
HDL_TAP"TRUE";
"B \NAC \NWC"7;
"S \NAC"
BN"9"30;
%"TAP"
"7","(-2100,2775)","0","mstr_standard","I92";
;
CDS_LIB"mstr_standard"
BODY_TYPE"PLUMBING"
HDL_TAP"TRUE";
"B \NAC \NWC"7;
"S \NAC"
BN"8"12;
%"RES"
"2","(-2900,3325)","0","mstr_discrete","I93";
;
CDS_SEC"1"
$SEC"1"
CDS_LOCATION"R775"
CDS_LIB"mstr_discrete"
ROOM"PCIE_STEERING"
$LOCATION"R775"
WATTAGE"1/16W"
TOLERANCE"5%"
VALUE"0.0"
PACK_TYPE"0402"
PART_NUMBER"G21497-005"
MATERIAL"CHIP";
"A"
$PN"1"28;
"B"
$PN"2"33;
%"RES"
"2","(-2700,3025)","0","mstr_discrete","I94";
;
CDS_SEC"1"
$SEC"1"
CDS_LOCATION"R778"
CDS_LIB"mstr_discrete"
ROOM"PCIE_STEERING"
$LOCATION"R778"
VALUE"0.0"
MATERIAL"CHIP"
WATTAGE"1/16W"
TOLERANCE"5%"
PART_NUMBER"G21497-005"
PACK_TYPE"0402";
"A"
$PN"1"29;
"B"
$PN"2"32;
%"TAP"
"3","(-2900,3575)","0","mstr_standard","I95";
;
CDS_LIB"mstr_standard"
BODY_TYPE"PLUMBING"
HDL_TAP"TRUE";
"B \NAC \NWC"8;
"S \NAC"
BN"12"28;
%"TAP"
"3","(-2700,3575)","0","mstr_standard","I96";
;
CDS_LIB"mstr_standard"
BODY_TYPE"PLUMBING"
HDL_TAP"TRUE";
"B \NAC \NWC"8;
"S \NAC"
BN"11"29;
%"RES"
"2","(-2500,3325)","0","mstr_discrete","I97";
;
CDS_SEC"1"
$SEC"1"
CDS_LOCATION"R780"
CDS_LIB"mstr_discrete"
ROOM"PCIE_STEERING"
$LOCATION"R780"
PACK_TYPE"0402"
MATERIAL"CHIP"
WATTAGE"1/16W"
TOLERANCE"5%"
VALUE"0.0"
PART_NUMBER"G21497-005";
"A"
$PN"1"26;
"B"
$PN"2"31;
%"RES"
"2","(-2300,3025)","0","mstr_discrete","I98";
;
CDS_SEC"1"
$SEC"1"
CDS_LOCATION"R782"
CDS_LIB"mstr_discrete"
ROOM"PCIE_STEERING"
PACK_TYPE"0402"
TOLERANCE"5%"
WATTAGE"1/16W"
MATERIAL"CHIP"
PART_NUMBER"G21497-005"
$LOCATION"R782"
VALUE"0.0";
"A"
$PN"1"27;
"B"
$PN"2"30;
%"RES"
"2","(-2100,3325)","0","mstr_discrete","I99";
;
CDS_SEC"1"
$SEC"1"
CDS_LOCATION"R784"
CDS_LIB"mstr_discrete"
ROOM"PCIE_STEERING"
$LOCATION"R784"
WATTAGE"1/16W"
VALUE"0.0"
TOLERANCE"5%"
MATERIAL"CHIP"
PACK_TYPE"0402"
PART_NUMBER"G21497-005";
"A"
$PN"1"25;
"B"
$PN"2"12;
END.
